FILE_TYPE = CONNECTIVITY;
{Allegro Design Entry HDL 17.2-2016 S066 (3851973) 4/6/2020}
"PAGE_NUMBER" = 16;
0"NC";
1"MUX3_SEL";
2"MUX1_SEL";
3"R_BNO080_RST_N";
4"R_BNO080_INT_N";
5"R_BNO080_BOOT_N";
6"SN_EEPROM_WP";
7"SEC_EEPROM_WP";
8"PCA9546_RST_N";
9"FPGA_IN_LM75B_INT3_N";
10"IO_L21P_16";
11"IO_L22P_16";
12"IO_L22N_16";
13"IO_L23P_16";
14"IO_L23N_16";
15"IO_L24N_16";
16"IO_L20P_34";
17"XP1R2V_FPGA_PG";
18"XP1R8V_FPGA_PG";
19"FPGA_IN_LM75B_INT2_N";
20"FPGA_IN_LM75B_INT1_N";
21"RGB_LED_SHUTDOWN_N";
22"R_SHT3X_RST_N";
23"R_SHT3X_ALERT_N";
24"SMA1_SIG_IN_BF_EN_N";
25"SMA3_SIG_IN_BF_EN_N";
26"SMA1_SIG_OUT_BF_EN_N";
27"SMA3_SIG_OUT_BF_EN_N";
28"SMA4_SIG_OUT_BF_EN_N";
29"XP12R0V_A_PG";
30"XP3R3V_EN";
31"XP3R3V_PG";
32"XP1R0V_FPGA_PG";
33"IO_L20N_34";
34"IO_L21P_34";
35"IO_L21N_34";
36"IO_L22P_34";
37"IO_L22N_34";
38"IO_L23P_34";
39"IO_L23N_34";
40"IO_L24P_34";
41"IO_L24N_34";
42"IO_L20P_35";
43"IO_L20N_35";
44"IO_L21P_35";
45"IO_L21N_35";
46"IO_L22P_35";
47"IO_L22N_35";
48"IO_L23P_35";
49"IO_L24P_35";
50"IO_L24N_35";
51"XP12R0V_A_FLTB";
52"FPGA_PROGRAM_N";
53"R_MAC_BITE OUT";
54"CLK_125M_OE";
55"MAC_ALARM";
56"FPGA_MGTRREF";
57"FPGA_IO_1";
58"FPGA_IO_2";
59"FPGA_IO_6";
60"FPGA_IO_7";
61"IO_L23N_35";
62"SMA2_SIG_OUT_BF_EN_N";
63"GPS_RST_N";
64"MUX2_SEL";
65"FT_USB_DETECT";
66"IO_L20P_16";
67"IO_L20N_16";
68"IO_L24P_16";
69"SMA4_SIG_IN_BF_EN_N";
70"XP12R0V_A_EN";
71"IO_L21N_16";
72"SMA2_SIG_IN_BF_EN_N";
73"CLK_200M_OE";
74"PCIE_CONN_PERST_N";
75"FPGA_DONE";
76"FPGA_IO_3";
77"FPGA_IO_5";
78"FPGA_IO_4";
79"FPGA_IO_0";
80"FPGA_IO_3";
81"UN$16$CONNHDR2X6FSSMT$I1614$8";
82"FPGA_IO_2";
83"UN$16$CONNHDR2X6FSSMT$I1614$6";
84"FPGA_IO_1";
85"UN$16$CONNHDR2X6FSSMT$I1614$4";
86"FPGA_IO_0";
87"UN$16$CONNHDR2X6FSSMT$I1614$2";
88"UN$16$CONNHDR2X6FSSMT$I1614$7";
89"UN$16$CONNHDR2X6FSSMT$I1614$5";
90"UN$16$CONNHDR2X6FSSMT$I1614$3";
91"UN$16$CONNHDR2X6FSSMT$I1614$1";
92"FPGA_IO_7";
93"FPGA_IO_6";
94"FPGA_IO_5";
95"FPGA_IO_4";
96"SG\g";
97"XP3R3V_FPGA\g";
98"XP5R0V_FT4232\g";
99"XP12R0V_IN\g";
100"XP3R3V_FPGA\g";
101"XP12R0V\g";
102"XP3R3V\g";
103"XP1R0V_FPGA\g";
104"XP1R2V_FPGA\g";
105"XP1R8V_FPGA\g";
106"XP2R5V_FPGA\g";
107"XP3R3V_FPGA\g";
108"XP5R0V\g";
109"XP3R3V_FT4232\g";
110"SG\g";
111"SG\g";
112"FPGA_CFG_INIT_N";
%"TP_PIONT"
"1","(-13300,8300)","2","cls","I1014";
;
$LOCATION"TP132"
CDS_LOCATION"TP132"
$SEC"1"
CDS_SEC"1"
CDS_LIB"cls"
CDS_LMAN_SYM_OUTLINE"-50,50,50,-50"
JEDEC_TYPE"TP010CT020B030_PTH"
BOM_IGNORE"TRUE";
"1 \B"
$PN"1"16;
%"TP_PIONT"
"1","(-13300,8200)","2","cls","I1015";
;
$LOCATION"TP133"
CDS_LOCATION"TP133"
$SEC"1"
CDS_SEC"1"
CDS_LIB"cls"
CDS_LMAN_SYM_OUTLINE"-50,50,50,-50"
JEDEC_TYPE"TP010CT020B030_PTH"
BOM_IGNORE"TRUE";
"1 \B"
$PN"1"33;
%"TP_PIONT"
"1","(-13300,8100)","2","cls","I1016";
;
$LOCATION"TP134"
CDS_LOCATION"TP134"
$SEC"1"
CDS_SEC"1"
BOM_IGNORE"TRUE"
JEDEC_TYPE"TP010CT020B030_PTH"
CDS_LMAN_SYM_OUTLINE"-50,50,50,-50"
CDS_LIB"cls";
"1 \B"
$PN"1"34;
%"TP_PIONT"
"1","(-13300,8000)","2","cls","I1017";
;
$LOCATION"TP135"
CDS_LOCATION"TP135"
$SEC"1"
CDS_SEC"1"
BOM_IGNORE"TRUE"
JEDEC_TYPE"TP010CT020B030_PTH"
CDS_LMAN_SYM_OUTLINE"-50,50,50,-50"
CDS_LIB"cls";
"1 \B"
$PN"1"35;
%"TP_PIONT"
"1","(-13300,7900)","2","cls","I1018";
;
$LOCATION"TP136"
CDS_LOCATION"TP136"
$SEC"1"
CDS_SEC"1"
BOM_IGNORE"TRUE"
JEDEC_TYPE"TP010CT020B030_PTH"
CDS_LMAN_SYM_OUTLINE"-50,50,50,-50"
CDS_LIB"cls";
"1 \B"
$PN"1"36;
%"TP_PIONT"
"1","(-13300,7800)","2","cls","I1019";
;
$LOCATION"TP137"
CDS_LOCATION"TP137"
$SEC"1"
CDS_SEC"1"
BOM_IGNORE"TRUE"
JEDEC_TYPE"TP010CT020B030_PTH"
CDS_LMAN_SYM_OUTLINE"-50,50,50,-50"
CDS_LIB"cls";
"1 \B"
$PN"1"37;
%"TP_PIONT"
"1","(-13300,7700)","2","cls","I1020";
;
$LOCATION"TP138"
CDS_LOCATION"TP138"
$SEC"1"
CDS_SEC"1"
BOM_IGNORE"TRUE"
JEDEC_TYPE"TP010CT020B030_PTH"
CDS_LMAN_SYM_OUTLINE"-50,50,50,-50"
CDS_LIB"cls";
"1 \B"
$PN"1"38;
%"TP_PIONT"
"1","(-13300,7600)","2","cls","I1021";
;
$LOCATION"TP139"
CDS_LOCATION"TP139"
$SEC"1"
CDS_SEC"1"
BOM_IGNORE"TRUE"
JEDEC_TYPE"TP010CT020B030_PTH"
CDS_LMAN_SYM_OUTLINE"-50,50,50,-50"
CDS_LIB"cls";
"1 \B"
$PN"1"39;
%"TP_PIONT"
"1","(-13300,7500)","2","cls","I1022";
;
$LOCATION"TP140"
CDS_LOCATION"TP140"
$SEC"1"
CDS_SEC"1"
BOM_IGNORE"TRUE"
JEDEC_TYPE"TP010CT020B030_PTH"
CDS_LMAN_SYM_OUTLINE"-50,50,50,-50"
CDS_LIB"cls";
"1 \B"
$PN"1"40;
%"TP_PIONT"
"1","(-13300,7400)","2","cls","I1023";
;
$LOCATION"TP141"
CDS_LOCATION"TP141"
$SEC"1"
CDS_SEC"1"
BOM_IGNORE"TRUE"
JEDEC_TYPE"TP010CT020B030_PTH"
CDS_LMAN_SYM_OUTLINE"-50,50,50,-50"
CDS_LIB"cls";
"1 \B"
$PN"1"41;
%"TP_PIONT"
"1","(-1000,8800)","0","cls","I1206";
;
$LOCATION"TP52"
CDS_LOCATION"TP52"
$SEC"1"
CDS_SEC"1"
CDS_LMAN_SYM_OUTLINE"-50,50,50,-50"
CDS_LIB"cls"
JEDEC_TYPE"TP010CT020B030_PTH"
BOM_IGNORE"TRUE";
"1 \B"
$PN"1"101;
%"VCC"
"1","(-2000,8900)","0","cls","I1207";
;
HDL_POWER"XP12R0V"
VOLTAGE"12V"
CDS_LIB"cls"
CDS_LMAN_SYM_OUTLINE"-250,250,250,-250"
BODY_TYPE"PLUMBING";
"$PIN0"101;
%"TP_PIONT"
"1","(-1000,8350)","0","cls","I1208";
;
$LOCATION"TP53"
CDS_LOCATION"TP53"
$SEC"1"
CDS_SEC"1"
CDS_LIB"cls"
CDS_LMAN_SYM_OUTLINE"-50,50,50,-50"
BOM_IGNORE"TRUE"
JEDEC_TYPE"TP010CT020B030_PTH";
"1 \B"
$PN"1"102;
%"VCC"
"1","(-2000,8450)","0","cls","I1209";
;
HDL_POWER"XP3R3V"
VOLTAGE"3.3"
CDS_LIB"cls"
CDS_LMAN_SYM_OUTLINE"-250,250,250,-250"
BODY_TYPE"PLUMBING";
"$PIN0"102;
%"TP_PIONT"
"1","(-1000,7900)","0","cls","I1210";
;
$LOCATION"TP54"
CDS_LOCATION"TP54"
$SEC"1"
CDS_SEC"1"
CDS_LIB"cls"
CDS_LMAN_SYM_OUTLINE"-50,50,50,-50"
BOM_IGNORE"TRUE"
JEDEC_TYPE"TP010CT020B030_PTH";
"1 \B"
$PN"1"103;
%"TP_PIONT"
"1","(-1000,7450)","0","cls","I1212";
;
$LOCATION"TP55"
CDS_LOCATION"TP55"
$SEC"1"
CDS_SEC"1"
JEDEC_TYPE"TP010CT020B030_PTH"
BOM_IGNORE"TRUE"
CDS_LMAN_SYM_OUTLINE"-50,50,50,-50"
CDS_LIB"cls";
"1 \B"
$PN"1"104;
%"TP_PIONT"
"1","(-1000,7000)","0","cls","I1215";
;
$LOCATION"TP56"
CDS_LOCATION"TP56"
$SEC"1"
CDS_SEC"1"
CDS_LIB"cls"
CDS_LMAN_SYM_OUTLINE"-50,50,50,-50"
BOM_IGNORE"TRUE"
JEDEC_TYPE"TP010CT020B030_PTH";
"1 \B"
$PN"1"105;
%"TP_PIONT"
"1","(-3300,9150)","0","cls","I1217";
;
$LOCATION"TP57"
CDS_LOCATION"TP57"
$SEC"1"
CDS_SEC"1"
JEDEC_TYPE"TP010CT020B030_PTH"
BOM_IGNORE"TRUE"
CDS_LMAN_SYM_OUTLINE"-50,50,50,-50"
CDS_LIB"cls";
"1 \B"
$PN"1"106;
%"TP_PIONT"
"1","(-3300,8700)","0","cls","I1219";
;
$LOCATION"TP58"
CDS_LOCATION"TP58"
$SEC"1"
CDS_SEC"1"
CDS_LIB"cls"
CDS_LMAN_SYM_OUTLINE"-50,50,50,-50"
BOM_IGNORE"TRUE"
JEDEC_TYPE"TP010CT020B030_PTH";
"1 \B"
$PN"1"107;
%"VCC"
"1","(-2000,8050)","0","cls","I1220";
;
HDL_POWER"XP1R0V_FPGA"
VOLTAGE"1.0V"
BODY_TYPE"PLUMBING"
CDS_LMAN_SYM_OUTLINE"-250,250,250,-250"
CDS_LIB"cls";
"$PIN0"103;
%"VCC"
"1","(-2000,7600)","0","cls","I1221";
;
VOLTAGE"1.2V"
HDL_POWER"XP1R2V_FPGA"
BODY_TYPE"PLUMBING"
CDS_LMAN_SYM_OUTLINE"-250,250,250,-250"
CDS_LIB"cls";
"$PIN0"104;
%"VCC"
"1","(-2000,7150)","0","cls","I1222";
;
HDL_POWER"XP1R8V_FPGA"
VOLTAGE"1.8V"
BODY_TYPE"PLUMBING"
CDS_LMAN_SYM_OUTLINE"-250,250,250,-250"
CDS_LIB"cls";
"$PIN0"105;
%"VCC"
"1","(-4300,9300)","0","cls","I1223";
;
HDL_POWER"XP2R5V_FPGA"
VOLTAGE"2.5V"
CDS_LIB"cls"
CDS_LMAN_SYM_OUTLINE"-250,250,250,-250"
BODY_TYPE"PLUMBING";
"$PIN0"106;
%"VCC"
"1","(-4300,8850)","0","cls","I1224";
;
VOLTAGE"3.3V"
HDL_POWER"XP3R3V_FPGA"
CDS_LMAN_SYM_OUTLINE"-250,250,250,-250"
CDS_LIB"cls"
BODY_TYPE"PLUMBING";
"$PIN0"107;
%"TP_PIONT"
"1","(-3300,8250)","0","cls","I1233";
;
$LOCATION"TP60"
CDS_LOCATION"TP60"
$SEC"1"
CDS_SEC"1"
CDS_LIB"cls"
CDS_LMAN_SYM_OUTLINE"-50,50,50,-50"
BOM_IGNORE"TRUE"
JEDEC_TYPE"TP010CT020B030_PTH";
"1 \B"
$PN"1"108;
%"VCC"
"1","(-4300,8400)","0","cls","I1234";
;
HDL_POWER"XP5R0V"
VOLTAGE"5.0"
BODY_TYPE"PLUMBING"
CDS_LIB"cls"
CDS_LMAN_SYM_OUTLINE"-250,250,250,-250";
"$PIN0"108;
%"TP_PIONT"
"1","(-12350,6550)","0","cls","I1487";
;
$LOCATION"TP193"
CDS_LOCATION"TP193"
$SEC"1"
CDS_SEC"1"
JEDEC_TYPE"TP010CT020B030_PTH"
BOM_IGNORE"TRUE"
CDS_LMAN_SYM_OUTLINE"-50,50,50,-50"
CDS_LIB"cls";
"1 \B"
$PN"1"44;
%"TP_PIONT"
"1","(-12350,6450)","0","cls","I1488";
;
$LOCATION"TP194"
CDS_LOCATION"TP194"
$SEC"1"
CDS_SEC"1"
JEDEC_TYPE"TP010CT020B030_PTH"
BOM_IGNORE"TRUE"
CDS_LMAN_SYM_OUTLINE"-50,50,50,-50"
CDS_LIB"cls";
"1 \B"
$PN"1"45;
%"TP_PIONT"
"1","(-12350,6150)","0","cls","I1489";
;
$LOCATION"TP195"
CDS_LOCATION"TP195"
$SEC"1"
CDS_SEC"1"
JEDEC_TYPE"TP010CT020B030_PTH"
BOM_IGNORE"TRUE"
CDS_LMAN_SYM_OUTLINE"-50,50,50,-50"
CDS_LIB"cls";
"1 \B"
$PN"1"48;
%"TP_PIONT"
"1","(-12350,6050)","0","cls","I1490";
;
$LOCATION"TP196"
CDS_LOCATION"TP196"
$SEC"1"
CDS_SEC"1"
JEDEC_TYPE"TP010CT020B030_PTH"
BOM_IGNORE"TRUE"
CDS_LMAN_SYM_OUTLINE"-50,50,50,-50"
CDS_LIB"cls";
"1 \B"
$PN"1"61;
%"TP_PIONT"
"1","(-13300,9050)","2","cls","I1505";
;
$LOCATION"TP183"
CDS_LOCATION"TP183"
$SEC"1"
CDS_SEC"1"
CDS_LIB"cls"
CDS_LMAN_SYM_OUTLINE"-50,50,50,-50"
BOM_IGNORE"TRUE"
JEDEC_TYPE"TP010CT020B030_PTH";
"1 \B"
$PN"1"11;
%"TP_PIONT"
"1","(-13300,8950)","2","cls","I1506";
;
$LOCATION"TP184"
CDS_LOCATION"TP184"
$SEC"1"
CDS_SEC"1"
CDS_LIB"cls"
CDS_LMAN_SYM_OUTLINE"-50,50,50,-50"
BOM_IGNORE"TRUE"
JEDEC_TYPE"TP010CT020B030_PTH";
"1 \B"
$PN"1"12;
%"TP_PIONT"
"1","(-13300,8850)","2","cls","I1507";
;
$LOCATION"TP185"
CDS_LOCATION"TP185"
$SEC"1"
CDS_SEC"1"
CDS_LIB"cls"
CDS_LMAN_SYM_OUTLINE"-50,50,50,-50"
BOM_IGNORE"TRUE"
JEDEC_TYPE"TP010CT020B030_PTH";
"1 \B"
$PN"1"13;
%"TP_PIONT"
"1","(-13300,8750)","2","cls","I1508";
;
$LOCATION"TP186"
CDS_LOCATION"TP186"
$SEC"1"
CDS_SEC"1"
CDS_LIB"cls"
CDS_LMAN_SYM_OUTLINE"-50,50,50,-50"
BOM_IGNORE"TRUE"
JEDEC_TYPE"TP010CT020B030_PTH";
"1 \B"
$PN"1"14;
%"TP_PIONT"
"1","(-13300,8650)","2","cls","I1509";
;
$LOCATION"TP187"
CDS_LOCATION"TP187"
$SEC"1"
CDS_SEC"1"
CDS_LIB"cls"
CDS_LMAN_SYM_OUTLINE"-50,50,50,-50"
BOM_IGNORE"TRUE"
JEDEC_TYPE"TP010CT020B030_PTH";
"1 \B"
$PN"1"68;
%"TP_PIONT"
"1","(-13300,8550)","2","cls","I1510";
;
$LOCATION"TP188"
CDS_LOCATION"TP188"
$SEC"1"
CDS_SEC"1"
CDS_LIB"cls"
CDS_LMAN_SYM_OUTLINE"-50,50,50,-50"
BOM_IGNORE"TRUE"
JEDEC_TYPE"TP010CT020B030_PTH";
"1 \B"
$PN"1"15;
%"TP_PIONT"
"1","(-13300,9400)","2","cls","I1511";
;
$LOCATION"TP180"
CDS_LOCATION"TP180"
$SEC"1"
CDS_SEC"1"
CDS_LIB"cls"
CDS_LMAN_SYM_OUTLINE"-50,50,50,-50"
BOM_IGNORE"TRUE"
JEDEC_TYPE"TP010CT020B030_PTH";
"1 \B"
$PN"1"67;
%"TP_PIONT"
"1","(-13300,9300)","2","cls","I1512";
;
$LOCATION"TP181"
CDS_LOCATION"TP181"
$SEC"1"
CDS_SEC"1"
CDS_LIB"cls"
CDS_LMAN_SYM_OUTLINE"-50,50,50,-50"
BOM_IGNORE"TRUE"
JEDEC_TYPE"TP010CT020B030_PTH";
"1 \B"
$PN"1"10;
%"TP_PIONT"
"1","(-13300,9200)","2","cls","I1513";
;
$LOCATION"TP182"
CDS_LOCATION"TP182"
$SEC"1"
CDS_SEC"1"
CDS_LIB"cls"
CDS_LMAN_SYM_OUTLINE"-50,50,50,-50"
BOM_IGNORE"TRUE"
JEDEC_TYPE"TP010CT020B030_PTH";
"1 \B"
$PN"1"71;
%"TP_PIONT"
"1","(-13300,9500)","2","cls","I1516";
;
$LOCATION"TP78"
CDS_LOCATION"TP78"
$SEC"1"
CDS_SEC"1"
CDS_LIB"cls"
CDS_LMAN_SYM_OUTLINE"-50,50,50,-50"
BOM_IGNORE"TRUE"
JEDEC_TYPE"TP010CT020B030_PTH";
"1 \B"
$PN"1"66;
%"TP_PIONT"
"1","(-12350,5950)","0","cls","I1523";
;
$LOCATION"TP203"
CDS_LOCATION"TP203"
$SEC"1"
CDS_SEC"1"
CDS_LIB"cls"
CDS_LMAN_SYM_OUTLINE"-50,50,50,-50"
BOM_IGNORE"TRUE"
JEDEC_TYPE"TP010CT020B030_PTH";
"1 \B"
$PN"1"49;
%"TP_PIONT"
"1","(-12350,5850)","0","cls","I1524";
;
$LOCATION"TP204"
CDS_LOCATION"TP204"
$SEC"1"
CDS_SEC"1"
CDS_LIB"cls"
CDS_LMAN_SYM_OUTLINE"-50,50,50,-50"
BOM_IGNORE"TRUE"
JEDEC_TYPE"TP010CT020B030_PTH";
"1 \B"
$PN"1"50;
%"TP_PIONT"
"1","(-12350,6750)","0","cls","I1527";
;
$LOCATION"TP199"
CDS_LOCATION"TP199"
$SEC"1"
CDS_SEC"1"
JEDEC_TYPE"TP010CT020B030_PTH"
BOM_IGNORE"TRUE"
CDS_LMAN_SYM_OUTLINE"-50,50,50,-50"
CDS_LIB"cls";
"1 \B"
$PN"1"42;
%"TP_PIONT"
"1","(-12350,6650)","0","cls","I1528";
;
$LOCATION"TP200"
CDS_LOCATION"TP200"
$SEC"1"
CDS_SEC"1"
JEDEC_TYPE"TP010CT020B030_PTH"
BOM_IGNORE"TRUE"
CDS_LMAN_SYM_OUTLINE"-50,50,50,-50"
CDS_LIB"cls";
"1 \B"
$PN"1"43;
%"TP_PIONT"
"1","(-12350,6350)","0","cls","I1529";
;
$LOCATION"TP201"
CDS_LOCATION"TP201"
$SEC"1"
CDS_SEC"1"
CDS_LIB"cls"
CDS_LMAN_SYM_OUTLINE"-50,50,50,-50"
BOM_IGNORE"TRUE"
JEDEC_TYPE"TP010CT020B030_PTH";
"1 \B"
$PN"1"46;
%"TP_PIONT"
"1","(-12350,6250)","0","cls","I1530";
;
$LOCATION"TP202"
CDS_LOCATION"TP202"
$SEC"1"
CDS_SEC"1"
CDS_LIB"cls"
CDS_LMAN_SYM_OUTLINE"-50,50,50,-50"
BOM_IGNORE"TRUE"
JEDEC_TYPE"TP010CT020B030_PTH";
"1 \B"
$PN"1"47;
%"GND_SG"
"1","(-12900,1650)","0","cls","I1540";
;
VOLTAGE"0"
HDL_POWER"SG"
CDS_LMAN_SYM_OUTLINE"0,0,100,-50"
CDS_LIB"cls"
BODY_TYPE"PLUMBING";
"SGND"96;
%"VCC"
"1","(-13000,4300)","0","cls","I1541";
;
HDL_POWER"XP3R3V_FPGA"
VOLTAGE"3.3V"
CDS_LIB"cls"
CDS_LMAN_SYM_OUTLINE"-250,250,250,-250"
BODY_TYPE"PLUMBING";
"$PIN0"97;
%"RESISTOR"
"2","(-12350,4000)","1","passive","I1542";
;
$LOCATION"R171"
CDS_LOCATION"R171"
$SEC"1"
CDS_SEC"1"
NO_ASSY"TRUE"
PACKAGE"0402"
VALUE"4.7KOHM"
TOLERANCE"1%"
CLS_PN"G155-14701-01"
CDS_LMAN_SYM_OUTLINE"-50,50,50,-100"
CDS_LIB"passive";
"1"
$PN"1"96;
"2"
$PN"2"79;
%"RESISTOR"
"2","(-12350,3700)","1","passive","I1544";
;
$LOCATION"R173"
CDS_LOCATION"R173"
$SEC"1"
CDS_SEC"1"
VALUE"4.7KOHM"
NO_ASSY"TRUE"
PACKAGE"0402"
TOLERANCE"1%"
CLS_PN"G155-14701-01"
CDS_LMAN_SYM_OUTLINE"-50,50,50,-100"
CDS_LIB"passive";
"1"
$PN"1"96;
"2"
$PN"2"57;
%"RESISTOR"
"2","(-12350,3400)","1","passive","I1547";
;
$LOCATION"R284"
CDS_LOCATION"R284"
$SEC"1"
CDS_SEC"1"
VALUE"4.7KOHM"
PACKAGE"0402"
NO_ASSY"TRUE"
CDS_LIB"passive"
CDS_LMAN_SYM_OUTLINE"-50,50,50,-100"
CLS_PN"G155-14701-01"
TOLERANCE"1%";
"1"
$PN"1"96;
"2"
$PN"2"58;
%"RESISTOR"
"2","(-12350,3100)","1","passive","I1549";
;
$LOCATION"R286"
CDS_LOCATION"R286"
$SEC"1"
CDS_SEC"1"
VALUE"4.7KOHM"
NO_ASSY"TRUE"
PACKAGE"0402"
CDS_LIB"passive"
CDS_LMAN_SYM_OUTLINE"-50,50,50,-100"
CLS_PN"G155-14701-01"
TOLERANCE"1%";
"1"
$PN"1"96;
"2"
$PN"2"76;
%"RESISTOR"
"2","(-12350,1900)","1","passive","I1550";
;
$LOCATION"R328"
CDS_LOCATION"R328"
$SEC"1"
CDS_SEC"1"
NO_ASSY"TRUE"
PACKAGE"0402"
VALUE"4.7KOHM"
TOLERANCE"1%"
CLS_PN"G155-14701-01"
CDS_LMAN_SYM_OUTLINE"-50,50,50,-100"
CDS_LIB"passive";
"1"
$PN"1"96;
"2"
$PN"2"60;
%"RESISTOR"
"2","(-12350,2200)","1","passive","I1552";
;
$LOCATION"R326"
CDS_LOCATION"R326"
$SEC"1"
CDS_SEC"1"
VALUE"4.7KOHM"
NO_ASSY"TRUE"
PACKAGE"0402"
TOLERANCE"1%"
CLS_PN"G155-14701-01"
CDS_LMAN_SYM_OUTLINE"-50,50,50,-100"
CDS_LIB"passive";
"1"
$PN"1"96;
"2"
$PN"2"59;
%"RESISTOR"
"2","(-12350,2800)","1","passive","I1555";
;
$LOCATION"R293"
CDS_LOCATION"R293"
$SEC"1"
CDS_SEC"1"
VALUE"4.7KOHM"
NO_ASSY"TRUE"
PACKAGE"0402"
CDS_LIB"passive"
CDS_LMAN_SYM_OUTLINE"-50,50,50,-100"
CLS_PN"G155-14701-01"
TOLERANCE"1%";
"1"
$PN"1"96;
"2"
$PN"2"78;
%"RESISTOR"
"2","(-12350,2500)","1","passive","I1557";
;
$LOCATION"R309"
CDS_LOCATION"R309"
$SEC"1"
CDS_SEC"1"
VALUE"4.7KOHM"
NO_ASSY"TRUE"
PACKAGE"0402"
CDS_LIB"passive"
CDS_LMAN_SYM_OUTLINE"-50,50,50,-100"
CLS_PN"G155-14701-01"
TOLERANCE"1%";
"1"
$PN"1"96;
"2"
$PN"2"77;
%"RESISTOR"
"1","(-12350,2300)","0","passive","I1602";
;
$LOCATION"R325"
CDS_LOCATION"R325"
$SEC"1"
CDS_SEC"1"
PACKAGE"0402"
VALUE"10KOHM"
TOLERANCE"1%"
CDS_LMAN_SYM_OUTLINE"-50,50,100,-50"
CDS_LIB"passive"
CLS_PN"G155-11002-01";
"1"
$PN"1"97;
"2"
$PN"2"59;
%"RESISTOR"
"1","(-12350,2000)","0","passive","I1603";
;
$LOCATION"R327"
CDS_LOCATION"R327"
$SEC"1"
CDS_SEC"1"
VALUE"10KOHM"
PACKAGE"0402"
TOLERANCE"1%"
CDS_LMAN_SYM_OUTLINE"-50,50,100,-50"
CDS_LIB"passive"
CLS_PN"G155-11002-01";
"1"
$PN"1"97;
"2"
$PN"2"60;
%"RESISTOR"
"1","(-12350,2600)","0","passive","I1604";
;
$LOCATION"R308"
CDS_LOCATION"R308"
$SEC"1"
CDS_SEC"1"
VALUE"10KOHM"
PACKAGE"0402"
TOLERANCE"1%"
CDS_LMAN_SYM_OUTLINE"-50,50,100,-50"
CDS_LIB"passive"
CLS_PN"G155-11002-01";
"1"
$PN"1"97;
"2"
$PN"2"77;
%"RESISTOR"
"1","(-12350,2900)","0","passive","I1605";
;
$LOCATION"R292"
CDS_LOCATION"R292"
$SEC"1"
CDS_SEC"1"
VALUE"10KOHM"
PACKAGE"0402"
TOLERANCE"1%"
CDS_LMAN_SYM_OUTLINE"-50,50,100,-50"
CDS_LIB"passive"
CLS_PN"G155-11002-01";
"1"
$PN"1"97;
"2"
$PN"2"78;
%"RESISTOR"
"1","(-12350,3200)","0","passive","I1606";
;
$LOCATION"R285"
CDS_LOCATION"R285"
$SEC"1"
CDS_SEC"1"
PACKAGE"0402"
VALUE"10KOHM"
TOLERANCE"1%"
CDS_LMAN_SYM_OUTLINE"-50,50,100,-50"
CDS_LIB"passive"
CLS_PN"G155-11002-01";
"1"
$PN"1"97;
"2"
$PN"2"76;
%"RESISTOR"
"1","(-12350,3800)","0","passive","I1607";
;
$LOCATION"R172"
CDS_LOCATION"R172"
$SEC"1"
CDS_SEC"1"
PACKAGE"0402"
VALUE"10KOHM"
TOLERANCE"1%"
CDS_LMAN_SYM_OUTLINE"-50,50,100,-50"
CDS_LIB"passive"
CLS_PN"G155-11002-01";
"1"
$PN"1"97;
"2"
$PN"2"57;
%"RESISTOR"
"1","(-12350,4100)","0","passive","I1608";
;
$LOCATION"R170"
CDS_LOCATION"R170"
$SEC"1"
CDS_SEC"1"
VALUE"10KOHM"
PACKAGE"0402"
TOLERANCE"1%"
CDS_LMAN_SYM_OUTLINE"-50,50,100,-50"
CDS_LIB"passive"
CLS_PN"G155-11002-01";
"1"
$PN"1"97;
"2"
$PN"2"79;
%"RESISTOR"
"1","(-12350,3500)","0","passive","I1609";
;
$LOCATION"R283"
CDS_LOCATION"R283"
$SEC"1"
CDS_SEC"1"
VALUE"10KOHM"
PACKAGE"0402"
TOLERANCE"1%"
CDS_LMAN_SYM_OUTLINE"-50,50,100,-50"
CDS_LIB"passive"
CLS_PN"G155-11002-01";
"1"
$PN"1"97;
"2"
$PN"2"58;
%"TP_PIONT"
"1","(-3300,7800)","0","cls","I1610";
;
$LOCATION"TP3"
CDS_LOCATION"TP3"
$SEC"1"
CDS_SEC"1"
BOM_IGNORE"TRUE"
JEDEC_TYPE"TP010CT020B030_PTH"
CDS_LMAN_SYM_OUTLINE"-50,50,50,-50"
CDS_LIB"cls";
"1 \B"
$PN"1"109;
%"VCC"
"1","(-4300,7950)","0","cls","I1611";
;
VOLTAGE"3.3V"
HDL_POWER"XP3R3V_FT4232"
CDS_LMAN_SYM_OUTLINE"-250,250,250,-250"
CDS_LIB"cls"
BODY_TYPE"PLUMBING";
"$PIN0"109;
%"TP_PIONT"
"1","(-3300,7350)","0","cls","I1612";
;
$LOCATION"TP4"
CDS_LOCATION"TP4"
$SEC"1"
CDS_SEC"1"
BOM_IGNORE"TRUE"
JEDEC_TYPE"TP010CT020B030_PTH"
CDS_LMAN_SYM_OUTLINE"-50,50,50,-50"
CDS_LIB"cls";
"1 \B"
$PN"1"98;
%"VCC"
"1","(-4300,7500)","0","cls","I1613";
;
VOLTAGE"5V"
HDL_POWER"XP5R0V_FT4232"
BODY_TYPE"PLUMBING"
CDS_LMAN_SYM_OUTLINE"-250,250,250,-250"
CDS_LIB"cls";
"$PIN0"98;
%"CONN_HDR_2X6_F_S_SMT"
"1","(-5900,2850)","4","connector","I1614";
;
LOCATION"J5"
$SEC"1"
CDS_SEC"1"
CLS_PN"G200-13133-01"
VALUE"SMH-106-02-L-D-TR"
CDS_LMAN_SYM_OUTLINE"0,0,400,-700"
CDS_LIB"connector";
"12"
$PN"12"100;
"10"
$PN"10"111;
"8"
$PN"8"81;
"6"
$PN"6"83;
"4"
$PN"4"85;
"2"
$PN"2"87;
"11"
$PN"11"100;
"9"
$PN"9"110;
"7"
$PN"7"88;
"5"
$PN"5"89;
"3"
$PN"3"90;
"1"
$PN"1"91;
%"TP_PIONT"
"1","(-10950,8550)","2","cls","I1615";
;
$LOCATION"TP20"
CDS_LOCATION"TP20"
$SEC"1"
CDS_SEC"1"
BOM_IGNORE"TRUE"
JEDEC_TYPE"TP010CT020B030_PTH"
CDS_LIB"cls"
CDS_LMAN_SYM_OUTLINE"-50,50,50,-50";
"1 \B"
$PN"1"7;
%"TP_PIONT"
"1","(-10950,9500)","2","cls","I1626";
;
$LOCATION"TP11"
CDS_LOCATION"TP11"
$SEC"1"
CDS_SEC"1"
JEDEC_TYPE"TP010CT020B030_PTH"
BOM_IGNORE"TRUE"
CDS_LMAN_SYM_OUTLINE"-50,50,50,-50"
CDS_LIB"cls";
"1 \B"
$PN"1"65;
%"TP_PIONT"
"1","(-10950,9400)","2","cls","I1627";
;
$LOCATION"TP12"
CDS_LOCATION"TP12"
$SEC"1"
CDS_SEC"1"
JEDEC_TYPE"TP010CT020B030_PTH"
BOM_IGNORE"TRUE"
CDS_LMAN_SYM_OUTLINE"-50,50,50,-50"
CDS_LIB"cls";
"1 \B"
$PN"1"1;
%"TP_PIONT"
"1","(-10950,9300)","2","cls","I1628";
;
$LOCATION"TP13"
CDS_LOCATION"TP13"
$SEC"1"
CDS_SEC"1"
JEDEC_TYPE"TP010CT020B030_PTH"
BOM_IGNORE"TRUE"
CDS_LMAN_SYM_OUTLINE"-50,50,50,-50"
CDS_LIB"cls";
"1 \B"
$PN"1"64;
%"TP_PIONT"
"1","(-10950,9200)","2","cls","I1629";
;
$LOCATION"TP14"
CDS_LOCATION"TP14"
$SEC"1"
CDS_SEC"1"
JEDEC_TYPE"TP010CT020B030_PTH"
BOM_IGNORE"TRUE"
CDS_LMAN_SYM_OUTLINE"-50,50,50,-50"
CDS_LIB"cls";
"1 \B"
$PN"1"2;
%"TP_PIONT"
"1","(-10950,9050)","2","cls","I1630";
;
$LOCATION"TP15"
CDS_LOCATION"TP15"
$SEC"1"
CDS_SEC"1"
BOM_IGNORE"TRUE"
JEDEC_TYPE"TP010CT020B030_PTH"
CDS_LIB"cls"
CDS_LMAN_SYM_OUTLINE"-50,50,50,-50";
"1 \B"
$PN"1"63;
%"TP_PIONT"
"1","(-10950,8950)","2","cls","I1631";
;
$LOCATION"TP16"
CDS_LOCATION"TP16"
$SEC"1"
CDS_SEC"1"
BOM_IGNORE"TRUE"
JEDEC_TYPE"TP010CT020B030_PTH"
CDS_LIB"cls"
CDS_LMAN_SYM_OUTLINE"-50,50,50,-50";
"1 \B"
$PN"1"3;
%"TP_PIONT"
"1","(-10950,8850)","2","cls","I1632";
;
$LOCATION"TP17"
CDS_LOCATION"TP17"
$SEC"1"
CDS_SEC"1"
BOM_IGNORE"TRUE"
JEDEC_TYPE"TP010CT020B030_PTH"
CDS_LIB"cls"
CDS_LMAN_SYM_OUTLINE"-50,50,50,-50";
"1 \B"
$PN"1"4;
%"TP_PIONT"
"1","(-10950,8750)","2","cls","I1633";
;
$LOCATION"TP18"
CDS_LOCATION"TP18"
$SEC"1"
CDS_SEC"1"
BOM_IGNORE"TRUE"
JEDEC_TYPE"TP010CT020B030_PTH"
CDS_LIB"cls"
CDS_LMAN_SYM_OUTLINE"-50,50,50,-50";
"1 \B"
$PN"1"5;
%"TP_PIONT"
"1","(-10950,8650)","2","cls","I1634";
;
$LOCATION"TP19"
CDS_LOCATION"TP19"
$SEC"1"
CDS_SEC"1"
BOM_IGNORE"TRUE"
JEDEC_TYPE"TP010CT020B030_PTH"
CDS_LIB"cls"
CDS_LMAN_SYM_OUTLINE"-50,50,50,-50";
"1 \B"
$PN"1"6;
%"TP_PIONT"
"1","(-10950,8350)","2","cls","I1645";
;
$LOCATION"TP21"
CDS_LOCATION"TP21"
$SEC"1"
CDS_SEC"1"
BOM_IGNORE"TRUE"
JEDEC_TYPE"TP010CT020B030_PTH"
CDS_LMAN_SYM_OUTLINE"-50,50,50,-50"
CDS_LIB"cls";
"1 \B"
$PN"1"8;
%"TP_PIONT"
"1","(-10950,8250)","2","cls","I1646";
;
$LOCATION"TP22"
CDS_LOCATION"TP22"
$SEC"1"
CDS_SEC"1"
BOM_IGNORE"TRUE"
JEDEC_TYPE"TP010CT020B030_PTH"
CDS_LMAN_SYM_OUTLINE"-50,50,50,-50"
CDS_LIB"cls";
"1 \B"
$PN"1"9;
%"TP_PIONT"
"1","(-10950,8150)","2","cls","I1647";
;
$LOCATION"TP23"
CDS_LOCATION"TP23"
$SEC"1"
CDS_SEC"1"
BOM_IGNORE"TRUE"
JEDEC_TYPE"TP010CT020B030_PTH"
CDS_LMAN_SYM_OUTLINE"-50,50,50,-50"
CDS_LIB"cls";
"1 \B"
$PN"1"19;
%"TP_PIONT"
"1","(-10950,8050)","2","cls","I1648";
;
$LOCATION"TP24"
CDS_LOCATION"TP24"
$SEC"1"
CDS_SEC"1"
BOM_IGNORE"TRUE"
JEDEC_TYPE"TP010CT020B030_PTH"
CDS_LMAN_SYM_OUTLINE"-50,50,50,-50"
CDS_LIB"cls";
"1 \B"
$PN"1"20;
%"TP_PIONT"
"1","(-10950,7900)","2","cls","I1649";
;
$LOCATION"TP25"
CDS_LOCATION"TP25"
$SEC"1"
CDS_SEC"1"
BOM_IGNORE"TRUE"
JEDEC_TYPE"TP010CT020B030_PTH"
CDS_LMAN_SYM_OUTLINE"-50,50,50,-50"
CDS_LIB"cls";
"1 \B"
$PN"1"21;
%"TP_PIONT"
"1","(-10950,6400)","2","cls","I1650";
;
$LOCATION"TP36"
CDS_LOCATION"TP36"
$SEC"1"
CDS_SEC"1"
CDS_LIB"cls"
CDS_LMAN_SYM_OUTLINE"-50,50,50,-50"
JEDEC_TYPE"TP010CT020B030_PTH"
BOM_IGNORE"TRUE";
"1 \B"
$PN"1"29;
%"TP_PIONT"
"1","(-10950,6100)","2","cls","I1651";
;
$LOCATION"TP38"
CDS_LOCATION"TP38"
$SEC"1"
CDS_SEC"1"
BOM_IGNORE"TRUE"
JEDEC_TYPE"TP010CT020B030_PTH"
CDS_LMAN_SYM_OUTLINE"-50,50,50,-50"
CDS_LIB"cls";
"1 \B"
$PN"1"31;
%"TP_PIONT"
"1","(-10950,6000)","2","cls","I1652";
;
$LOCATION"TP39"
CDS_LOCATION"TP39"
$SEC"1"
CDS_SEC"1"
BOM_IGNORE"TRUE"
JEDEC_TYPE"TP010CT020B030_PTH"
CDS_LMAN_SYM_OUTLINE"-50,50,50,-50"
CDS_LIB"cls";
"1 \B"
$PN"1"32;
%"TP_PIONT"
"1","(-10950,5900)","2","cls","I1653";
;
$LOCATION"TP40"
CDS_LOCATION"TP40"
$SEC"1"
CDS_SEC"1"
BOM_IGNORE"TRUE"
JEDEC_TYPE"TP010CT020B030_PTH"
CDS_LMAN_SYM_OUTLINE"-50,50,50,-50"
CDS_LIB"cls";
"1 \B"
$PN"1"17;
%"TP_PIONT"
"1","(-10950,5800)","2","cls","I1654";
;
$LOCATION"TP41"
CDS_LOCATION"TP41"
$SEC"1"
CDS_SEC"1"
BOM_IGNORE"TRUE"
JEDEC_TYPE"TP010CT020B030_PTH"
CDS_LMAN_SYM_OUTLINE"-50,50,50,-50"
CDS_LIB"cls";
"1 \B"
$PN"1"18;
%"TP_PIONT"
"1","(-10950,7700)","2","cls","I1660";
;
$LOCATION"TP26"
CDS_LOCATION"TP26"
$SEC"1"
CDS_SEC"1"
CDS_LIB"cls"
CDS_LMAN_SYM_OUTLINE"-50,50,50,-50"
JEDEC_TYPE"TP010CT020B030_PTH"
BOM_IGNORE"TRUE";
"1 \B"
$PN"1"22;
%"TP_PIONT"
"1","(-10950,7600)","2","cls","I1661";
;
$LOCATION"TP27"
CDS_LOCATION"TP27"
$SEC"1"
CDS_SEC"1"
CDS_LIB"cls"
CDS_LMAN_SYM_OUTLINE"-50,50,50,-50"
JEDEC_TYPE"TP010CT020B030_PTH"
BOM_IGNORE"TRUE";
"1 \B"
$PN"1"23;
%"TP_PIONT"
"1","(-10950,7000)","2","cls","I1662";
;
$LOCATION"TP32"
CDS_LOCATION"TP32"
$SEC"1"
CDS_SEC"1"
CDS_LIB"cls"
CDS_LMAN_SYM_OUTLINE"-50,50,50,-50"
JEDEC_TYPE"TP010CT020B030_PTH"
BOM_IGNORE"TRUE";
"1 \B"
$PN"1"26;
%"TP_PIONT"
"1","(-10950,6200)","2","cls","I1663";
;
$LOCATION"TP59"
CDS_LOCATION"TP59"
$SEC"1"
CDS_SEC"1"
CDS_LIB"cls"
CDS_LMAN_SYM_OUTLINE"-50,50,50,-50"
BOM_IGNORE"TRUE"
JEDEC_TYPE"TP010CT020B030_PTH";
"1 \B"
$PN"1"30;
%"TP_PIONT"
"1","(-1000,9200)","0","cls","I1665";
;
$LOCATION"TP42"
CDS_LOCATION"TP42"
$SEC"1"
CDS_SEC"1"
JEDEC_TYPE"TP010CT020B030_PTH"
BOM_IGNORE"TRUE"
CDS_LMAN_SYM_OUTLINE"-50,50,50,-50"
CDS_LIB"cls";
"1 \B"
$PN"1"99;
%"VCC"
"1","(-2000,9350)","0","cls","I1666";
;
VOLTAGE"12"
HDL_POWER"XP12R0V_IN"
BODY_TYPE"PLUMBING"
CDS_LMAN_SYM_OUTLINE"-250,250,250,-250"
CDS_LIB"cls";
"$PIN0"99;
%"TP_PIONT"
"1","(-10950,7450)","2","cls","I1667";
;
$LOCATION"TP28"
CDS_LOCATION"TP28"
$SEC"1"
CDS_SEC"1"
BOM_IGNORE"TRUE"
JEDEC_TYPE"TP010CT020B030_PTH"
CDS_LMAN_SYM_OUTLINE"-50,50,50,-50"
CDS_LIB"cls";
"1 \B"
$PN"1"24;
%"TP_PIONT"
"1","(-10950,6900)","2","cls","I1669";
;
$LOCATION"TP33"
CDS_LOCATION"TP33"
$SEC"1"
CDS_SEC"1"
BOM_IGNORE"TRUE"
JEDEC_TYPE"TP010CT020B030_PTH"
CDS_LMAN_SYM_OUTLINE"-50,50,50,-50"
CDS_LIB"cls";
"1 \B"
$PN"1"62;
%"TP_PIONT"
"1","(-10950,7350)","2","cls","I1672";
;
$LOCATION"TP29"
CDS_LOCATION"TP29"
$SEC"1"
CDS_SEC"1"
BOM_IGNORE"TRUE"
JEDEC_TYPE"TP010CT020B030_PTH"
CDS_LMAN_SYM_OUTLINE"-50,50,50,-50"
CDS_LIB"cls";
"1 \B"
$PN"1"72;
%"TP_PIONT"
"1","(-10950,6800)","2","cls","I1673";
;
$LOCATION"TP34"
CDS_LOCATION"TP34"
$SEC"1"
CDS_SEC"1"
CDS_LIB"cls"
CDS_LMAN_SYM_OUTLINE"-50,50,50,-50"
JEDEC_TYPE"TP010CT020B030_PTH"
BOM_IGNORE"TRUE";
"1 \B"
$PN"1"27;
%"TP_PIONT"
"1","(-10950,6700)","2","cls","I1675";
;
$LOCATION"TP35"
CDS_LOCATION"TP35"
$SEC"1"
CDS_SEC"1"
CDS_LIB"cls"
CDS_LMAN_SYM_OUTLINE"-50,50,50,-50"
JEDEC_TYPE"TP010CT020B030_PTH"
BOM_IGNORE"TRUE";
"1 \B"
$PN"1"28;
%"TP_PIONT"
"1","(-10950,7250)","2","cls","I1678";
;
$LOCATION"TP30"
CDS_LOCATION"TP30"
$SEC"1"
CDS_SEC"1"
CDS_LIB"cls"
CDS_LMAN_SYM_OUTLINE"-50,50,50,-50"
JEDEC_TYPE"TP010CT020B030_PTH"
BOM_IGNORE"TRUE";
"1 \B"
$PN"1"25;
%"TP_PIONT"
"1","(-10950,7150)","2","cls","I1679";
;
$LOCATION"TP31"
CDS_LOCATION"TP31"
$SEC"1"
CDS_SEC"1"
BOM_IGNORE"TRUE"
JEDEC_TYPE"TP010CT020B030_PTH"
CDS_LMAN_SYM_OUTLINE"-50,50,50,-50"
CDS_LIB"cls";
"1 \B"
$PN"1"69;
%"TP_PIONT"
"1","(-10950,6300)","2","cls","I1682";
;
$LOCATION"TP37"
CDS_LOCATION"TP37"
$SEC"1"
CDS_SEC"1"
CDS_LIB"cls"
CDS_LMAN_SYM_OUTLINE"-50,50,50,-50"
JEDEC_TYPE"TP010CT020B030_PTH"
BOM_IGNORE"TRUE";
"1 \B"
$PN"1"51;
%"TP_PIONT"
"1","(-8250,9300)","2","cls","I1684";
;
$LOCATION"TP46"
CDS_LOCATION"TP46"
$SEC"1"
CDS_SEC"1"
CDS_LMAN_SYM_OUTLINE"-50,50,50,-50"
CDS_LIB"cls"
JEDEC_TYPE"TP010CT020B030_PTH"
BOM_IGNORE"TRUE";
"1 \B"
$PN"1"112;
%"TP_PIONT"
"1","(-8250,9500)","2","cls","I1689";
;
$LOCATION"TP44"
CDS_LOCATION"TP44"
$SEC"1"
CDS_SEC"1"
CDS_LIB"cls"
CDS_LMAN_SYM_OUTLINE"-50,50,50,-50"
BOM_IGNORE"TRUE"
JEDEC_TYPE"TP010CT020B030_PTH";
"1 \B"
$PN"1"75;
%"TP_PIONT"
"1","(-8250,9400)","2","cls","I1690";
;
$LOCATION"TP45"
CDS_LOCATION"TP45"
$SEC"1"
CDS_SEC"1"
CDS_LIB"cls"
CDS_LMAN_SYM_OUTLINE"-50,50,50,-50"
BOM_IGNORE"TRUE"
JEDEC_TYPE"TP010CT020B030_PTH";
"1 \B"
$PN"1"52;
%"TP_PIONT"
"1","(-10950,6500)","2","cls","I1691";
;
$LOCATION"TP43"
CDS_LOCATION"TP43"
$SEC"1"
CDS_SEC"1"
CDS_LIB"cls"
CDS_LMAN_SYM_OUTLINE"-50,50,50,-50"
BOM_IGNORE"TRUE"
JEDEC_TYPE"TP010CT020B030_PTH";
"1 \B"
$PN"1"70;
%"TP_PIONT"
"1","(-8250,9200)","2","cls","I1693";
;
$LOCATION"TP47"
CDS_LOCATION"TP47"
$SEC"1"
CDS_SEC"1"
CDS_LIB"cls"
CDS_LMAN_SYM_OUTLINE"-50,50,50,-50"
JEDEC_TYPE"TP010CT020B030_PTH"
BOM_IGNORE"TRUE";
"1 \B"
$PN"1"56;
%"TP_PIONT"
"1","(-8250,9000)","2","cls","I1695";
;
$LOCATION"TP48"
CDS_LOCATION"TP48"
$SEC"1"
CDS_SEC"1"
JEDEC_TYPE"TP010CT020B030_PTH"
BOM_IGNORE"TRUE"
CDS_LIB"cls"
CDS_LMAN_SYM_OUTLINE"-50,50,50,-50";
"1 \B"
$PN"1"74;
%"TP_PIONT"
"1","(-8250,8850)","2","cls","I1699";
;
$LOCATION"TP49"
CDS_LOCATION"TP49"
$SEC"1"
CDS_SEC"1"
BOM_IGNORE"TRUE"
JEDEC_TYPE"TP010CT020B030_PTH"
CDS_LMAN_SYM_OUTLINE"-50,50,50,-50"
CDS_LIB"cls";
"1 \B"
$PN"1"73;
%"TP_PIONT"
"1","(-8250,8750)","2","cls","I1701";
;
$LOCATION"TP50"
CDS_LOCATION"TP50"
$SEC"1"
CDS_SEC"1"
BOM_IGNORE"TRUE"
JEDEC_TYPE"TP010CT020B030_PTH"
CDS_LMAN_SYM_OUTLINE"-50,50,50,-50"
CDS_LIB"cls";
"1 \B"
$PN"1"54;
%"TP_PIONT"
"1","(-8250,8500)","2","cls","I1704";
;
$LOCATION"TP51"
CDS_LOCATION"TP51"
$SEC"1"
CDS_SEC"1"
CDS_LIB"cls"
CDS_LMAN_SYM_OUTLINE"-50,50,50,-50"
JEDEC_TYPE"TP010CT020B030_PTH"
BOM_IGNORE"TRUE";
"1 \B"
$PN"1"55;
%"TP_PIONT"
"1","(-8250,8400)","2","cls","I1705";
;
$LOCATION"TP62"
CDS_LOCATION"TP62"
$SEC"1"
CDS_SEC"1"
CDS_LIB"cls"
CDS_LMAN_SYM_OUTLINE"-50,50,50,-50"
JEDEC_TYPE"TP010CT020B030_PTH"
BOM_IGNORE"TRUE";
"1 \B"
$PN"1"53;
%"RESISTOR"
"1","(-7150,2950)","0","passive","I1706";
;
$LOCATION"R430"
CDS_LOCATION"R430"
$SEC"1"
CDS_SEC"1"
PACKAGE"0402"
VALUE"33OHM"
TOLERANCE"1%"
CLS_PN"G155-133R0-01"
CDS_LMAN_SYM_OUTLINE"-50,50,100,-50"
CDS_LIB"passive";
"1"
$PN"1"95;
"2"
$PN"2"91;
%"RESISTOR"
"1","(-7150,3250)","0","passive","I1707";
;
$LOCATION"R329"
CDS_LOCATION"R329"
$SEC"1"
CDS_SEC"1"
PACKAGE"0402"
VALUE"33OHM"
TOLERANCE"1%"
CLS_PN"G155-133R0-01"
CDS_LMAN_SYM_OUTLINE"-50,50,100,-50"
CDS_LIB"passive";
"1"
$PN"1"92;
"2"
$PN"2"88;
%"RESISTOR"
"1","(-7150,3150)","0","passive","I1708";
;
$LOCATION"R428"
CDS_LOCATION"R428"
$SEC"1"
CDS_SEC"1"
PACKAGE"0402"
VALUE"33OHM"
CDS_LIB"passive"
CDS_LMAN_SYM_OUTLINE"-50,50,100,-50"
CLS_PN"G155-133R0-01"
TOLERANCE"1%";
"1"
$PN"1"93;
"2"
$PN"2"89;
%"RESISTOR"
"1","(-7150,3050)","0","passive","I1709";
;
$LOCATION"R429"
CDS_LOCATION"R429"
$SEC"1"
CDS_SEC"1"
PACKAGE"0402"
VALUE"33OHM"
TOLERANCE"1%"
CLS_PN"G155-133R0-01"
CDS_LMAN_SYM_OUTLINE"-50,50,100,-50"
CDS_LIB"passive";
"1"
$PN"1"94;
"2"
$PN"2"90;
%"RESISTOR"
"1","(-5100,3250)","0","passive","I1718";
;
$LOCATION"R431"
CDS_LOCATION"R431"
$SEC"1"
CDS_SEC"1"
PACKAGE"0402"
VALUE"33OHM"
TOLERANCE"1%"
CLS_PN"G155-133R0-01"
CDS_LMAN_SYM_OUTLINE"-50,50,100,-50"
CDS_LIB"passive";
"1"
$PN"1"81;
"2"
$PN"2"80;
%"RESISTOR"
"1","(-5100,3150)","0","passive","I1719";
;
$LOCATION"R432"
CDS_LOCATION"R432"
$SEC"1"
CDS_SEC"1"
PACKAGE"0402"
VALUE"33OHM"
CDS_LIB"passive"
CDS_LMAN_SYM_OUTLINE"-50,50,100,-50"
CLS_PN"G155-133R0-01"
TOLERANCE"1%";
"1"
$PN"1"83;
"2"
$PN"2"82;
%"RESISTOR"
"1","(-5100,3050)","0","passive","I1720";
;
$LOCATION"R433"
CDS_LOCATION"R433"
$SEC"1"
CDS_SEC"1"
PACKAGE"0402"
VALUE"33OHM"
TOLERANCE"1%"
CLS_PN"G155-133R0-01"
CDS_LMAN_SYM_OUTLINE"-50,50,100,-50"
CDS_LIB"passive";
"1"
$PN"1"85;
"2"
$PN"2"84;
%"RESISTOR"
"1","(-5100,2950)","0","passive","I1721";
;
$LOCATION"R434"
CDS_LOCATION"R434"
$SEC"1"
CDS_SEC"1"
PACKAGE"0402"
VALUE"33OHM"
TOLERANCE"1%"
CLS_PN"G155-133R0-01"
CDS_LMAN_SYM_OUTLINE"-50,50,100,-50"
CDS_LIB"passive";
"1"
$PN"1"87;
"2"
$PN"2"86;
%"VCC"
"1","(-6500,3800)","0","cls","I1722";
;
VOLTAGE"3.3V"
HDL_POWER"XP3R3V_FPGA"
CDS_LIB"cls"
CDS_LMAN_SYM_OUTLINE"-250,250,250,-250"
BODY_TYPE"PLUMBING";
"$PIN0"100;
%"GND_SG"
"1","(-6500,2700)","0","cls","I1723";
;
HDL_POWER"SG"
BODY_TYPE"PLUMBING"
CDS_LMAN_SYM_OUTLINE"0,0,100,-50"
CDS_LIB"cls";
"SGND"110;
%"GND_SG"
"1","(-5800,2700)","0","cls","I1724";
;
HDL_POWER"SG"
BODY_TYPE"PLUMBING"
CDS_LMAN_SYM_OUTLINE"0,0,100,-50"
CDS_LIB"cls";
"SGND"111;
END.
